#ISCELL
  mstr_symbols intel_corp_bpage *
  *
#ISCELL
  mstr_standard tap *
  page245_i10
#ISCELL
  mstr_standard tap *
  page245_i11
#ISCELL
  mstr_standard tap *
  page245_i12
#ISCELL
  mstr_standard tap *
  page245_i13
#ISCELL
  mstr_standard tap *
  page245_i14
#ISCELL
  mstr_standard tap *
  page245_i15
#ISCELL
  mstr_standard tap *
  page245_i16
#ISCELL
  mstr_standard tap *
  page245_i17
#ISCELL
  mstr_standard tap *
  page245_i18
#ISCELL
  mstr_symbols gnd *
  page245_i19
#ISCELL
  mstr_symbols gnd *
  page245_i20
#ISCELL
  mstr_standard offpage *
  page245_i21
#ISCELL
  mstr_standard offpage *
  page245_i22
#ISCELL
  mstr_symbols gnd *
  page245_i25
#ISCELL
  mstr_symbols gnd *
  page245_i27
#ISCELL
  mstr_standard tap *
  page245_i29
#ISCELL
  mstr_standard tap *
  page245_i30
#ISCELL
  mstr_standard tap *
  page245_i31
#ISCELL
  mstr_standard tap *
  page245_i32
#ISCELL
  mstr_standard tap *
  page245_i33
#ISCELL
  mstr_standard tap *
  page245_i34
#ISCELL
  mstr_standard tap *
  page245_i35
#ISCELL
  mstr_standard tap *
  page245_i36
#ISCELL
  mstr_standard tap *
  page245_i37
#ISCELL
  mstr_standard tap *
  page245_i38
#ISCELL
  mstr_standard tap *
  page245_i39
#ISCELL
  mstr_standard tap *
  page245_i40
#ISCELL
  mstr_standard tap *
  page245_i41
#ISCELL
  mstr_standard tap *
  page245_i42
#ISCELL
  mstr_standard tap *
  page245_i43
#ISCELL
  mstr_standard tap *
  page245_i44
#ISCELL
  mstr_standard offpage *
  page245_i45
#ISCELL
  mstr_standard offpage *
  page245_i46
#CELL
  w_hdl smc-conn60a-22-gp *
  page245_i48
#ISCELL
  mstr_standard tap *
  page245_i5
#ISCELL
  mstr_standard tap *
  page245_i52
#ISCELL
  mstr_standard tap *
  page245_i53
#ISCELL
  mstr_standard offpage *
  page245_i54
#ISCELL
  mstr_standard offpage *
  page245_i55
#CELL
  mstr_discrete res *
  page245_i56
#CELL
  mstr_discrete res *
  page245_i57
#CELL
  mstr_discrete res *
  page245_i58
#CELL
  mstr_discrete res *
  page245_i59
#ISCELL
  mstr_standard tap *
  page245_i6
#CELL
  mstr_discrete res *
  page245_i60
#ISCELL
  mstr_standard offpage *
  page245_i61
#CELL
  mstr_ttl 74cbtlv1g125 *
  page245_i64
#CELL
  mstr_analog nc7sb3157 *
  page245_i66
#ISCELL
  mstr_symbols p3v3_stby *
  page245_i67
#ISCELL
  mstr_standard tap *
  page245_i7
#CELL
  dev_discrete cap_a *
  page245_i71
#ISCELL
  mstr_symbols gnd *
  page245_i72
#CELL
  dev_discrete cap_a *
  page245_i74
#ISCELL
  mstr_symbols gnd *
  page245_i75
#ISCELL
  mstr_standard offpage *
  page245_i77
#CELL
  mstr_discrete res *
  page245_i78
#ISCELL
  mstr_symbols p3v3_stby *
  page245_i79
#ISCELL
  mstr_standard tap *
  page245_i8
#ISCELL
  mstr_standard offpage *
  page245_i80
#ISCELL
  mstr_standard offpage *
  page245_i81
#ISCELL
  mstr_standard offpage *
  page245_i82
#ISCELL
  mstr_standard offpage *
  page245_i83
#ISCELL
  mstr_standard tap *
  page245_i9
